#ISCELL
  mstr_symbols intel_corp_bpage *
  *
#ISCELL
  mstr_standard offpage *
  page249_i1
#ISCELL
  mstr_symbols gnd *
  page249_i10
#ISCELL
  mstr_symbols gnd *
  page249_i11
#CELL
  mstr_discrete res *
  page249_i12
#ISCELL
  mstr_symbols gnd *
  page249_i14
#CELL
  w_hdl lmv331idckrg4-gp *
  page249_i15
#ISCELL
  mstr_symbols p3v3_stby *
  page249_i16
#CELL
  mstr_discrete res *
  page249_i17
#ISCELL
  mstr_symbols gnd *
  page249_i18
#ISCELL
  mstr_symbols p3v3_stby *
  page249_i19
#CELL
  mstr_discrete res *
  page249_i2
#ISCELL
  mstr_symbols gnd *
  page249_i20
#CELL
  mstr_discrete cap *
  page249_i21
#ISCELL
  mstr_standard offpage *
  page249_i22
#ISCELL
  mstr_symbols p3v3_stby *
  page249_i24
#CELL
  mstr_discrete npn *
  page249_i26
#CELL
  mstr_discrete res *
  page249_i27
#ISCELL
  mstr_standard offpage *
  page249_i28
#CELL
  mstr_discrete npn *
  page249_i29
#ISCELL
  mstr_symbols gnd *
  page249_i3
#CELL
  mstr_discrete fet_n *
  page249_i30
#CELL
  w_hdl 47kr2f-gp *
  page249_i31
#CELL
  mstr_discrete cap *
  page249_i32
#CELL
  w_hdl 82k5r2f-gp *
  page249_i33
#ISCELL
  mstr_standard offpage *
  page249_i5
#ISCELL
  mstr_symbols gnd *
  page249_i6
#CELL
  mstr_discrete res *
  page249_i7
#CELL
  mstr_discrete res *
  page249_i8
#ISCELL
  mstr_symbols p3v3_stby *
  page249_i9
